# T6G (Grand Teton) — schematic netlist excerpt (pin names and nets, part order shuffled) for the footprints in the layout excerpt that follows; sources: Cadence DE-HDL packaged netlist, KiCad conversion of 04192023_DAF0TMB3IC0_F0TG_MB_C_brd_V02_OCP.brd

U246  NC7SB3157  NC7SB3157P6X EMPTY  pkg SMLF  page 143
  B1  = OCP_V3_2_NOT_PRSNT_RBT_ARB_IN
  GND  = GND
  B0  = OCP_V3_2_RBT_ARB_OUT
  A  = OCP_SFF_RBT_ARB_IN_MUX1
  VCC  = P3V3_AUX
  S  = OCP_V3_2_PRSNT_ALL_R1_N

R4135  Q_RES  10K 1% CHIP  pkg 0402LF  page 125 : A = P3V3_AUX ; B = PRSNT_CABLE_GPU_A2_N

(kicad_pcb
	(version 20260206)
	(generator "pcbnew")
	(generator_version "10.0")
	(general
		(thickness 1.6)
		(legacy_teardrops no)
	)
	(paper "A4")
	(title_block
		(title "04192023_DAF0TMB3IC0_F0TG_MB_C_brd_V02_OCP.brd")
		(comment 1 "Grand Teton / footprints 4122-4123 of 8354")
	)
	(layers
		(0 "F.Cu" signal "TOP")
		(4 "In1.Cu" signal "GND")
		(6 "In2.Cu" signal "IN1")
		(8 "In3.Cu" signal "GND1")
		(10 "In4.Cu" signal "IN2")
		(12 "In5.Cu" signal "GND2")
		(14 "In6.Cu" signal "IN3")
		(16 "In7.Cu" signal "GND3")
		(18 "In8.Cu" signal "VCC")
		(20 "In9.Cu" signal "VCC1")
		(22 "In10.Cu" signal "GND4")
		(24 "In11.Cu" signal "IN4")
		(26 "In12.Cu" signal "GND5")
		(28 "In13.Cu" signal "IN5")
		(30 "In14.Cu" signal "GND6")
		(32 "In15.Cu" signal "IN6")
		(34 "In16.Cu" signal "GND7")
		(2 "B.Cu" signal "BOTTOM")
		(9 "F.Adhes" user "F.Adhesive")
		(11 "B.Adhes" user "B.Adhesive")
		(13 "F.Paste" user "Package Geometry/Pastemask Top")
		(15 "B.Paste" user "Package Geometry/Pastemask Bottom")
		(5 "F.SilkS" user "Ref Des/Silkscreen Top")
		(7 "B.SilkS" user "Ref Des/Silkscreen Bottom")
		(1 "F.Mask" user "Board Geometry/Soldermask Top")
		(3 "B.Mask" user "Board Geometry/Soldermask Bottom")
		(17 "Dwgs.User" user "User.Drawings")
		(19 "Cmts.User" user "User.Comments")
		(21 "Eco1.User" user "User.Eco1")
		(23 "Eco2.User" user "User.Eco2")
		(25 "Edge.Cuts" user "Board Geometry/Outline")
		(27 "Margin" user)
		(31 "F.CrtYd" user "Package Geometry/Place Bound Top")
		(29 "B.CrtYd" user "Package Geometry/Place Bound Bottom")
		(35 "F.Fab" user "Ref Des/Assembly Top")
		(33 "B.Fab" user "Ref Des/Assembly Bottom")
	)
	(footprint ""
		(layer "F.Cu")
		(at 308.198266 -430.240186 180)
		(property "Reference" "R4135"
			(at 0 0 180)
			(layer "F.SilkS")
			(hide yes)
			(effects
				(font
					(size 1.27 1.27)
				)
			)
		)
		(property "Value" ""
			(at 0 0 180)
			(layer "F.Fab")
			(effects
				(font
					(size 1.27 1.27)
				)
			)
		)
		(duplicate_pad_numbers_are_jumpers no)
		(fp_line
			(start 0.7874 0.4064)
			(end -0.7874 0.4064)
			(stroke
				(width 0.1524)
				(type default)
			)
			(layer "F.SilkS")
		)
		(fp_line
			(start 0.7874 -0.4064)
			(end 0.7874 0.4064)
			(stroke
				(width 0.1524)
				(type default)
			)
			(layer "F.SilkS")
		)
		(fp_line
			(start -0.7874 0.4064)
			(end -0.7874 -0.4064)
			(stroke
				(width 0.1524)
				(type default)
			)
			(layer "F.SilkS")
		)
		(fp_line
			(start -0.7874 -0.4064)
			(end 0.7874 -0.4064)
			(stroke
				(width 0.1524)
				(type default)
			)
			(layer "F.SilkS")
		)
		(fp_line
			(start 0.67945 0.3048)
			(end 0.120396 0.3048)
			(stroke
				(width 0.1)
				(type default)
			)
			(layer "F.Fab")
		)
		(fp_line
			(start 0.67945 -0.3048)
			(end 0.67945 0.3048)
			(stroke
				(width 0.1)
				(type default)
			)
			(layer "F.Fab")
		)
		(fp_line
			(start 0.12065 -0.2794)
			(end 0.12065 -0.3048)
			(stroke
				(width 0.1)
				(type default)
			)
			(layer "F.Fab")
		)
		(fp_line
			(start 0.12065 -0.3048)
			(end 0.67945 -0.3048)
			(stroke
				(width 0.1)
				(type default)
			)
			(layer "F.Fab")
		)
		(fp_line
			(start 0.120396 0.3048)
			(end 0.120396 0.2794)
			(stroke
				(width 0.1)
				(type default)
			)
			(layer "F.Fab")
		)
		(fp_line
			(start 0.120396 0.2794)
			(end -0.12065 0.2794)
			(stroke
				(width 0.1)
				(type default)
			)
			(layer "F.Fab")
		)
		(fp_line
			(start -0.12065 0.3048)
			(end -0.67945 0.3048)
			(stroke
				(width 0.1)
				(type default)
			)
			(layer "F.Fab")
		)
		(fp_line
			(start -0.12065 0.2794)
			(end -0.12065 0.3048)
			(stroke
				(width 0.1)
				(type default)
			)
			(layer "F.Fab")
		)
		(fp_line
			(start -0.12065 -0.2794)
			(end 0.12065 -0.2794)
			(stroke
				(width 0.1)
				(type default)
			)
			(layer "F.Fab")
		)
		(fp_line
			(start -0.12065 -0.305054)
			(end -0.12065 -0.2794)
			(stroke
				(width 0.1)
				(type default)
			)
			(layer "F.Fab")
		)
		(fp_line
			(start -0.67945 0.3048)
			(end -0.67945 -0.305054)
			(stroke
				(width 0.1)
				(type default)
			)
			(layer "F.Fab")
		)
		(fp_line
			(start -0.67945 -0.305054)
			(end -0.12065 -0.305054)
			(stroke
				(width 0.1)
				(type default)
			)
			(layer "F.Fab")
		)
		(pad "1" smd circle
			(at -0.40005 0 180)
			(size 0 0)
			(layers "F.Cu" "F.Mask" "F.Paste")
			(net "P3V3_AUX")
		)
		(pad "2" smd circle
			(at 0.40005 0 180)
			(size 0 0)
			(layers "F.Cu" "F.Mask" "F.Paste")
			(net "PRSNT_CABLE_GPU_A2_N")
		)
	)
	(footprint ""
		(layer "F.Cu")
		(at 144.74063 -98.355658)
		(property "Reference" "U246"
			(at 0.1651 -1.72847 0)
			(unlocked yes)
			(layer "F.SilkS")
			(effects
				(font
					(size 0.7874 0.5842)
					(thickness 0.1524)
				)
			)
		)
		(property "Value" ""
			(at 0 0 0)
			(layer "F.Fab")
			(effects
				(font
					(size 1.27 1.27)
				)
			)
		)
		(duplicate_pad_numbers_are_jumpers no)
		(fp_line
			(start -1.7272 1.1176)
			(end -1.7272 -1.1176)
			(stroke
				(width 0.1524)
				(type default)
			)
			(layer "F.SilkS")
		)
		(fp_line
			(start -0.254 -1.1176)
			(end -1.7272 -1.1176)
			(stroke
				(width 0.1524)
				(type default)
			)
			(layer "F.SilkS")
		)
		(fp_line
			(start 0 -0.7366)
			(end -0.254 -1.1176)
			(stroke
				(width 0.1524)
				(type default)
			)
			(layer "F.SilkS")
		)
		(fp_line
			(start 0.254 -1.1176)
			(end 0 -0.7366)
			(stroke
				(width 0.1524)
				(type default)
			)
			(layer "F.SilkS")
		)
		(fp_line
			(start 1.7272 -1.1176)
			(end 0.254 -1.1176)
			(stroke
				(width 0.1524)
				(type default)
			)
			(layer "F.SilkS")
		)
		(fp_line
			(start 1.7272 -1.1176)
			(end 1.7272 1.1176)
			(stroke
				(width 0.1524)
				(type default)
			)
			(layer "F.SilkS")
		)
		(fp_line
			(start 1.7272 1.1176)
			(end -1.7272 1.1176)
			(stroke
				(width 0.1524)
				(type default)
			)
			(layer "F.SilkS")
		)
		(fp_poly
			(pts
				(xy -2.7178 -1.030986) (xy -1.9558 -0.649986) (xy -2.7178 -0.268986)
			)
			(stroke
				(width 0)
				(type default)
			)
			(fill yes)
			(layer "F.SilkS")
		)
		(fp_line
			(start -1.5748 -1.1176)
			(end -1.5748 1.1176)
			(stroke
				(width 0.1)
				(type default)
			)
			(layer "F.Fab")
		)
		(fp_line
			(start -1.5748 1.1176)
			(end 1.5748 1.1176)
			(stroke
				(width 0.1)
				(type default)
			)
			(layer "F.Fab")
		)
		(fp_line
			(start 1.5748 -1.1176)
			(end -1.5748 -1.1176)
			(stroke
				(width 0.1)
				(type default)
			)
			(layer "F.Fab")
		)
		(fp_line
			(start 1.5748 1.1176)
			(end 1.5748 -1.1176)
			(stroke
				(width 0.1)
				(type default)
			)
			(layer "F.Fab")
		)
		(fp_poly
			(pts
				(xy -1.9558 -0.649986) (xy -2.7178 -0.268986) (xy -2.7178 -1.030986)
			)
			(stroke
				(width 0)
				(type default)
			)
			(fill yes)
			(layer "F.Fab")
		)
		(pad "1" smd rect
			(at -0.999998 -0.649986 270)
			(size 0.3556 1.1176)
			(layers "F.Cu" "F.Mask" "F.Paste")
			(net "OCP_V3_2_NOT_PRSNT_RBT_ARB_IN")
		)
		(pad "2" smd rect
			(at -0.999998 0 270)
			(size 0.3556 1.1176)
			(layers "F.Cu" "F.Mask" "F.Paste")
			(net "GND")
		)
		(pad "3" smd rect
			(at -0.999998 0.649986 270)
			(size 0.3556 1.1176)
			(layers "F.Cu" "F.Mask" "F.Paste")
			(net "OCP_V3_2_RBT_ARB_OUT")
		)
		(pad "4" smd rect
			(at 0.999998 0.649986 270)
			(size 0.3556 1.1176)
			(layers "F.Cu" "F.Mask" "F.Paste")
			(net "OCP_SFF_RBT_ARB_IN_MUX1")
		)
		(pad "5" smd rect
			(at 0.999998 0 270)
			(size 0.3556 1.1176)
			(layers "F.Cu" "F.Mask" "F.Paste")
			(net "P3V3_AUX")
		)
		(pad "6" smd rect
			(at 0.999998 -0.649986 270)
			(size 0.3556 1.1176)
			(layers "F.Cu" "F.Mask" "F.Paste")
			(net "OCP_V3_2_PRSNT_ALL_R1_N")
		)
	)
)
